(kicad_pcb
	(version 20241229)
	(generator "pcbnew")
	(generator_version "9.0")
	(general
		(thickness 1.294)
		(legacy_teardrops no)
	)
	(paper "A3")
	(title_block
		(title "Kintex 410T devboard")
		(date "2024-04-03")
		(rev "1.1.2")
		(comment 9 "footprint 170 of 975 (U1), pads 356-415 of 900")
	)
	(layers
		(0 "F.Cu" mixed)
		(4 "In1.Cu" power)
		(6 "In2.Cu" power)
		(8 "In3.Cu" mixed)
		(10 "In4.Cu" power)
		(12 "In5.Cu" mixed)
		(14 "In6.Cu" power)
		(16 "In7.Cu" mixed)
		(18 "In8.Cu" power)
		(2 "B.Cu" mixed)
		(9 "F.Adhes" user "F.Adhesive")
		(11 "B.Adhes" user "B.Adhesive")
		(13 "F.Paste" user)
		(15 "B.Paste" user)
		(5 "F.SilkS" user "F.Silkscreen")
		(7 "B.SilkS" user "B.Silkscreen")
		(1 "F.Mask" user)
		(3 "B.Mask" user)
		(17 "Dwgs.User" user "User.Drawings")
		(19 "Cmts.User" user "User.Comments")
		(21 "Eco1.User" user "User.Eco1")
		(23 "Eco2.User" user "User.Eco2")
		(25 "Edge.Cuts" user)
		(27 "Margin" user)
		(31 "F.CrtYd" user "F.Courtyard")
		(29 "B.CrtYd" user "B.Courtyard")
		(35 "F.Fab" user)
		(33 "B.Fab" user)
	)
	(footprint "antmicro-footprints:BGA-900_31x31mm_Layout30x30_P1x1mm_FFG900"
		(locked yes)
		(layer "F.Cu")
		(at 200 130)
		(property "Reference" "U1"
			(at -15.74 -15.78 0)
			(layer "F.SilkS")
			(effects
				(font
					(size 0.7 0.7)
					(thickness 0.15)
				)
				(justify left bottom)
			)
		)
		(property "Value" "XC7K410T-2FFG900I"
			(at -4.436 17.635 0)
			(layer "F.Fab")
			(effects
				(font
					(size 0.7 0.7)
					(thickness 0.15)
				)
				(justify left bottom)
			)
		)
		(property "Description" "FPGA, Kintex-7, MMCM, PLL, 350 I/O's, 710 MHz, 406720 Cells, 970 mV to 1.03 V, FCBGA-900"
			(at 0 0 0)
			(layer "F.Fab")
			(hide yes)
			(effects
				(font
					(size 1.27 1.27)
					(thickness 0.15)
				)
			)
		)
		(property "Author" "Antmicro"
			(at 0 0 0)
			(layer "F.Fab")
			(hide yes)
			(effects
				(font
					(size 1 1)
					(thickness 0.15)
				)
			)
		)
		(property "License" "Apache-2.0"
			(at 0 0 0)
			(layer "F.Fab")
			(hide yes)
			(effects
				(font
					(size 1 1)
					(thickness 0.15)
				)
			)
		)
		(property "MPN" "XC7K410T-2FFG900I"
			(at 0 0 0)
			(layer "F.Fab")
			(hide yes)
			(effects
				(font
					(size 1 1)
					(thickness 0.15)
				)
			)
		)
		(property "Manufacturer" "AMD-Xilinx"
			(at 0 0 0)
			(layer "F.Fab")
			(hide yes)
			(effects
				(font
					(size 1 1)
					(thickness 0.15)
				)
			)
		)
		(sheetname "FPGA supply")
		(sheetfile "fpga-supply.kicad_sch")
		(attr smd)
		(pad "B26" smd circle
			(at 10.5 -13.5)
			(size 0.5 0.5)
			(property pad_prop_bga)
			(layers "F.Cu" "F.Mask" "F.Paste")
			(net 3 "VCC_USR_B")
			(pinfunction "VCCO_16")
			(pintype "passive")
			(solder_mask_margin 0.02)
		)
		(pad "B27" smd circle
			(at 11.5 -13.5)
			(size 0.5 0.5)
			(property pad_prop_bga)
			(layers "F.Cu" "F.Mask" "F.Paste")
			(net 1275 "/USER_IO.B12")
			(pinfunction "IO_L7P_T1_16")
			(pintype "bidirectional")
			(die_length 20.903)
			(solder_mask_margin 0.02)
		)
		(pad "B28" smd circle
			(at 12.5 -13.5)
			(size 0.5 0.5)
			(property pad_prop_bga)
			(layers "F.Cu" "F.Mask" "F.Paste")
			(net 1277 "/USER_IO.B15")
			(pinfunction "IO_L9P_T1_DQS_16")
			(pintype "bidirectional")
			(die_length 23.114)
			(solder_mask_margin 0.02)
		)
		(pad "B29" smd circle
			(at 13.5 -13.5)
			(size 0.5 0.5)
			(property pad_prop_bga)
			(layers "F.Cu" "F.Mask" "F.Paste")
			(net 417 "/FPGA Bank 16 & 17/USR_FLASH_1.DQ3")
			(pinfunction "IO_L15N_T2_DQS_16")
			(pintype "bidirectional")
			(die_length 22.831)
			(solder_mask_margin 0.02)
		)
		(pad "B30" smd circle
			(at 14.5 -13.5)
			(size 0.5 0.5)
			(property pad_prop_bga)
			(layers "F.Cu" "F.Mask" "F.Paste")
			(net 782 "unconnected-(U1C-IO_L17P_T2_16-PadB30)")
			(pinfunction "IO_L17P_T2_16")
			(pintype "bidirectional+no_connect")
			(die_length 24.67)
			(solder_mask_margin 0.02)
		)
		(pad "C1" smd circle
			(at -14.5 -12.5)
			(size 0.5 0.5)
			(property pad_prop_bga)
			(layers "F.Cu" "F.Mask" "F.Paste")
			(net 1 "GND")
			(pinfunction "GND")
			(pintype "passive")
			(solder_mask_margin 0.02)
		)
		(pad "C2" smd circle
			(at -13.5 -12.5)
			(size 0.5 0.5)
			(property pad_prop_bga)
			(layers "F.Cu" "F.Mask" "F.Paste")
			(net 1 "GND")
			(pinfunction "GND")
			(pintype "passive")
			(solder_mask_margin 0.02)
		)
		(pad "C3" smd circle
			(at -12.5 -12.5)
			(size 0.5 0.5)
			(property pad_prop_bga)
			(layers "F.Cu" "F.Mask" "F.Paste")
			(net 929 "unconnected-(U1G-MGTXTXN1_118-PadC3)")
			(pinfunction "MGTXTXN1_118")
			(pintype "bidirectional+no_connect")
			(die_length 14.029)
			(solder_mask_margin 0.02)
		)
		(pad "C4" smd circle
			(at -11.5 -12.5)
			(size 0.5 0.5)
			(property pad_prop_bga)
			(layers "F.Cu" "F.Mask" "F.Paste")
			(net 930 "unconnected-(U1G-MGTXTXP1_118-PadC4)")
			(pinfunction "MGTXTXP1_118")
			(pintype "bidirectional+no_connect")
			(die_length 14.008)
			(solder_mask_margin 0.02)
		)
		(pad "C5" smd circle
			(at -10.5 -12.5)
			(size 0.5 0.5)
			(property pad_prop_bga)
			(layers "F.Cu" "F.Mask" "F.Paste")
			(net 8 "+1V2_MGTAVTT")
			(pinfunction "MGTAVTT")
			(pintype "passive")
			(solder_mask_margin 0.02)
		)
		(pad "C6" smd circle
			(at -9.5 -12.5)
			(size 0.5 0.5)
			(property pad_prop_bga)
			(layers "F.Cu" "F.Mask" "F.Paste")
			(net 1 "GND")
			(pinfunction "GND")
			(pintype "passive")
			(solder_mask_margin 0.02)
		)
		(pad "C7" smd circle
			(at -8.5 -12.5)
			(size 0.5 0.5)
			(property pad_prop_bga)
			(layers "F.Cu" "F.Mask" "F.Paste")
			(net 931 "unconnected-(U1G-MGTREFCLK0N_118-PadC7)")
			(pinfunction "MGTREFCLK0N_118")
			(pintype "bidirectional+no_connect")
			(die_length 12.106)
			(solder_mask_margin 0.02)
		)
		(pad "C8" smd circle
			(at -7.5 -12.5)
			(size 0.5 0.5)
			(property pad_prop_bga)
			(layers "F.Cu" "F.Mask" "F.Paste")
			(net 932 "unconnected-(U1G-MGTREFCLK0P_118-PadC8)")
			(pinfunction "MGTREFCLK0P_118")
			(pintype "bidirectional+no_connect")
			(die_length 11.647)
			(solder_mask_margin 0.02)
		)
		(pad "C9" smd circle
			(at -6.5 -12.5)
			(size 0.5 0.5)
			(property pad_prop_bga)
			(layers "F.Cu" "F.Mask" "F.Paste")
			(net 1 "GND")
			(pinfunction "GND")
			(pintype "passive")
			(solder_mask_margin 0.02)
		)
		(pad "C10" smd circle
			(at -5.5 -12.5)
			(size 0.5 0.5)
			(property pad_prop_bga)
			(layers "F.Cu" "F.Mask" "F.Paste")
			(net 800 "unconnected-(U1J-VCCBATT_0-PadC10)")
			(pinfunction "VCCBATT_0")
			(pintype "bidirectional+no_connect")
			(die_length 28.237)
			(solder_mask_margin 0.02)
		)
		(pad "C11" smd circle
			(at -4.5 -12.5)
			(size 0.5 0.5)
			(property pad_prop_bga)
			(layers "F.Cu" "F.Mask" "F.Paste")
			(net 241 "/FMC+ HSPC/FMC.IO18_N")
			(pinfunction "IO_L18N_T2_18")
			(pintype "bidirectional")
			(die_length 23.774)
			(solder_mask_margin 0.02)
		)
		(pad "C12" smd circle
			(at -3.5 -12.5)
			(size 0.5 0.5)
			(property pad_prop_bga)
			(layers "F.Cu" "F.Mask" "F.Paste")
			(net 643 "/FMC+ HSPC/FMC.IO15_P")
			(pinfunction "IO_L15P_T2_DQS_18")
			(pintype "bidirectional")
			(die_length 25.474)
			(solder_mask_margin 0.02)
		)
		(pad "C13" smd circle
			(at -2.5 -12.5)
			(size 0.5 0.5)
			(property pad_prop_bga)
			(layers "F.Cu" "F.Mask" "F.Paste")
			(net 24 "+3V3")
			(pinfunction "VCCO_18")
			(pintype "bidirectional")
			(solder_mask_margin 0.02)
		)
		(pad "C14" smd circle
			(at -1.5 -12.5)
			(size 0.5 0.5)
			(property pad_prop_bga)
			(layers "F.Cu" "F.Mask" "F.Paste")
			(net 437 "/FMC+ HSPC/FMC.IO21_N")
			(pinfunction "IO_L21N_T3_DQS_18")
			(pintype "bidirectional")
			(die_length 22.366)
			(solder_mask_margin 0.02)
		)
		(pad "C15" smd circle
			(at -0.5 -12.5)
			(size 0.5 0.5)
			(property pad_prop_bga)
			(layers "F.Cu" "F.Mask" "F.Paste")
			(net 445 "/FMC+ HSPC/FMC.IO23_P")
			(pinfunction "IO_L23P_T3_18")
			(pintype "bidirectional")
			(die_length 22.399)
			(solder_mask_margin 0.02)
		)
		(pad "C16" smd circle
			(at 0.5 -12.5)
			(size 0.5 0.5)
			(property pad_prop_bga)
			(layers "F.Cu" "F.Mask" "F.Paste")
			(net 496 "/FPGA Bank 12 & 13/USB_HOST.~{RESET}")
			(pinfunction "IO_L15N_T2_DQS_17")
			(pintype "bidirectional")
			(die_length 23.846)
			(solder_mask_margin 0.02)
		)
		(pad "C17" smd circle
			(at 1.5 -12.5)
			(size 0.5 0.5)
			(property pad_prop_bga)
			(layers "F.Cu" "F.Mask" "F.Paste")
			(net 938 "/FPGA Bank 12 & 13/USB_HOST.MOSI")
			(pinfunction "IO_L17P_T2_17")
			(pintype "bidirectional")
			(die_length 23.901)
			(solder_mask_margin 0.02)
		)
		(pad "C18" smd circle
			(at 2.5 -12.5)
			(size 0.5 0.5)
			(property pad_prop_bga)
			(layers "F.Cu" "F.Mask" "F.Paste")
			(net 1 "GND")
			(pinfunction "GND")
			(pintype "passive")
			(solder_mask_margin 0.02)
		)
		(pad "C19" smd circle
			(at 3.5 -12.5)
			(size 0.5 0.5)
			(property pad_prop_bga)
			(layers "F.Cu" "F.Mask" "F.Paste")
			(net 524 "/FPGA Bank 16 & 17/HDMI.D2_P")
			(pinfunction "IO_L24P_T3_17")
			(pintype "bidirectional")
			(die_length 25.069)
			(solder_mask_margin 0.02)
		)
		(pad "C20" smd circle
			(at 4.5 -12.5)
			(size 0.5 0.5)
			(property pad_prop_bga)
			(layers "F.Cu" "F.Mask" "F.Paste")
			(net 526 "/FPGA Bank 16 & 17/HDMI.D1_P")
			(pinfunction "IO_L19P_T3_17")
			(pintype "bidirectional")
			(die_length 23.681)
			(solder_mask_margin 0.02)
		)
		(pad "C21" smd circle
			(at 5.5 -12.5)
			(size 0.5 0.5)
			(property pad_prop_bga)
			(layers "F.Cu" "F.Mask" "F.Paste")
			(net 529 "/FPGA Bank 16 & 17/HDMI.D0_N")
			(pinfunction "IO_L8N_T1_17")
			(pintype "bidirectional")
			(die_length 16.277)
			(solder_mask_margin 0.02)
		)
		(pad "C22" smd circle
			(at 6.5 -12.5)
			(size 0.5 0.5)
			(property pad_prop_bga)
			(layers "F.Cu" "F.Mask" "F.Paste")
			(net 939 "/FPGA Bank 16 & 17/GBE_RGMII.TXD0")
			(pinfunction "IO_L10N_T1_17")
			(pintype "bidirectional")
			(die_length 16.905)
			(solder_mask_margin 0.02)
		)
		(pad "C23" smd circle
			(at 7.5 -12.5)
			(size 0.5 0.5)
			(property pad_prop_bga)
			(layers "F.Cu" "F.Mask" "F.Paste")
			(net 3 "VCC_USR_B")
			(pinfunction "VCCO_16")
			(pintype "passive")
			(solder_mask_margin 0.02)
		)
		(pad "C24" smd circle
			(at 8.5 -12.5)
			(size 0.5 0.5)
			(property pad_prop_bga)
			(layers "F.Cu" "F.Mask" "F.Paste")
			(net 1280 "/USER_IO.B18")
			(pinfunction "IO_L8P_T1_16")
			(pintype "bidirectional")
			(die_length 20.699)
			(solder_mask_margin 0.02)
		)
		(pad "C25" smd circle
			(at 9.5 -12.5)
			(size 0.5 0.5)
			(property pad_prop_bga)
			(layers "F.Cu" "F.Mask" "F.Paste")
			(net 1276 "/USER_IO.B14")
			(pinfunction "IO_L12P_T1_MRCC_16")
			(pintype "bidirectional")
			(die_length 21.617)
			(solder_mask_margin 0.02)
		)
		(pad "C26" smd circle
			(at 10.5 -12.5)
			(size 0.5 0.5)
			(property pad_prop_bga)
			(layers "F.Cu" "F.Mask" "F.Paste")
			(net 1269 "/USER_IO.B6")
			(pinfunction "IO_L11N_T1_SRCC_16")
			(pintype "bidirectional")
			(die_length 20.862)
			(solder_mask_margin 0.02)
		)
		(pad "C27" smd circle
			(at 11.5 -12.5)
			(size 0.5 0.5)
			(property pad_prop_bga)
			(layers "F.Cu" "F.Mask" "F.Paste")
			(net 1290 "/USER_IO.B30")
			(pinfunction "IO_L13N_T2_MRCC_16")
			(pintype "bidirectional")
			(die_length 20.889)
			(solder_mask_margin 0.02)
		)
		(pad "C28" smd circle
			(at 12.5 -12.5)
			(size 0.5 0.5)
			(property pad_prop_bga)
			(layers "F.Cu" "F.Mask" "F.Paste")
			(net 1 "GND")
			(pinfunction "GND")
			(pintype "passive")
			(solder_mask_margin 0.02)
		)
		(pad "C29" smd circle
			(at 13.5 -12.5)
			(size 0.5 0.5)
			(property pad_prop_bga)
			(layers "F.Cu" "F.Mask" "F.Paste")
			(net 420 "/FPGA Bank 16 & 17/USR_FLASH_1.~{CS}")
			(pinfunction "IO_L15P_T2_DQS_16")
			(pintype "bidirectional")
			(die_length 22.768)
			(solder_mask_margin 0.02)
		)
		(pad "C30" smd circle
			(at 14.5 -12.5)
			(size 0.5 0.5)
			(property pad_prop_bga)
			(layers "F.Cu" "F.Mask" "F.Paste")
			(net 427 "/FPGA Bank 16 & 17/USR_FLASH_1.CLK")
			(pinfunction "IO_L16N_T2_16")
			(pintype "bidirectional")
			(die_length 23.33)
			(solder_mask_margin 0.02)
		)
		(pad "D1" smd circle
			(at -14.5 -11.5)
			(size 0.5 0.5)
			(property pad_prop_bga)
			(layers "F.Cu" "F.Mask" "F.Paste")
			(net 976 "unconnected-(U1G-MGTXTXN0_118-PadD1)")
			(pinfunction "MGTXTXN0_118")
			(pintype "bidirectional+no_connect")
			(die_length 16.063)
			(solder_mask_margin 0.02)
		)
		(pad "D2" smd circle
			(at -13.5 -11.5)
			(size 0.5 0.5)
			(property pad_prop_bga)
			(layers "F.Cu" "F.Mask" "F.Paste")
			(net 977 "unconnected-(U1G-MGTXTXP0_118-PadD2)")
			(pinfunction "MGTXTXP0_118")
			(pintype "bidirectional+no_connect")
			(die_length 16.112)
			(solder_mask_margin 0.02)
		)
		(pad "D3" smd circle
			(at -12.5 -11.5)
			(size 0.5 0.5)
			(property pad_prop_bga)
			(layers "F.Cu" "F.Mask" "F.Paste")
			(net 8 "+1V2_MGTAVTT")
			(pinfunction "MGTAVTT")
			(pintype "passive")
			(solder_mask_margin 0.02)
		)
		(pad "D4" smd circle
			(at -11.5 -11.5)
			(size 0.5 0.5)
			(property pad_prop_bga)
			(layers "F.Cu" "F.Mask" "F.Paste")
			(net 1 "GND")
			(pinfunction "GND")
			(pintype "passive")
			(solder_mask_margin 0.02)
		)
		(pad "D5" smd circle
			(at -10.5 -11.5)
			(size 0.5 0.5)
			(property pad_prop_bga)
			(layers "F.Cu" "F.Mask" "F.Paste")
			(net 978 "unconnected-(U1G-MGTXRXN1_118-PadD5)")
			(pinfunction "MGTXRXN1_118")
			(pintype "bidirectional+no_connect")
			(die_length 11.844)
			(solder_mask_margin 0.02)
		)
		(pad "D6" smd circle
			(at -9.5 -11.5)
			(size 0.5 0.5)
			(property pad_prop_bga)
			(layers "F.Cu" "F.Mask" "F.Paste")
			(net 982 "unconnected-(U1G-MGTXRXP1_118-PadD6)")
			(pinfunction "MGTXRXP1_118")
			(pintype "bidirectional+no_connect")
			(die_length 12)
			(solder_mask_margin 0.02)
		)
		(pad "D7" smd circle
			(at -8.5 -11.5)
			(size 0.5 0.5)
			(property pad_prop_bga)
			(layers "F.Cu" "F.Mask" "F.Paste")
			(net 6 "+1V0_MGTAVCC")
			(pinfunction "MGTAVCC")
			(pintype "passive")
			(solder_mask_margin 0.02)
		)
		(pad "D8" smd circle
			(at -7.5 -11.5)
			(size 0.5 0.5)
			(property pad_prop_bga)
			(layers "F.Cu" "F.Mask" "F.Paste")
			(net 1 "GND")
			(pinfunction "GND")
			(pintype "passive")
			(solder_mask_margin 0.02)
		)
		(pad "D9" smd circle
			(at -6.5 -11.5)
			(size 0.5 0.5)
			(property pad_prop_bga)
			(layers "F.Cu" "F.Mask" "F.Paste")
			(net 1 "GND")
			(pinfunction "GND")
			(pintype "passive")
			(solder_mask_margin 0.02)
		)
		(pad "D10" smd circle
			(at -5.5 -11.5)
			(size 0.5 0.5)
			(property pad_prop_bga)
			(layers "F.Cu" "F.Mask" "F.Paste")
			(net 24 "+3V3")
			(pinfunction "VCCO_18")
			(pintype "passive")
			(solder_mask_margin 0.02)
		)
		(pad "D11" smd circle
			(at -4.5 -11.5)
			(size 0.5 0.5)
			(property pad_prop_bga)
			(layers "F.Cu" "F.Mask" "F.Paste")
			(net 254 "/FMC+ HSPC/FMC.IO18_P")
			(pinfunction "IO_L18P_T2_18")
			(pintype "bidirectional")
			(die_length 23.711)
			(solder_mask_margin 0.02)
		)
		(pad "D12" smd circle
			(at -3.5 -11.5)
			(size 0.5 0.5)
			(property pad_prop_bga)
			(layers "F.Cu" "F.Mask" "F.Paste")
			(net 424 "/FMC+ HSPC/FMC.IO13_P")
			(pinfunction "IO_L13P_T2_MRCC_18")
			(pintype "bidirectional")
			(die_length 22.434)
			(solder_mask_margin 0.02)
		)
		(pad "D13" smd circle
			(at -2.5 -11.5)
			(size 0.5 0.5)
			(property pad_prop_bga)
			(layers "F.Cu" "F.Mask" "F.Paste")
			(net 423 "/FMC+ HSPC/FMC.IO13_N")
			(pinfunction "IO_L13N_T2_MRCC_18")
			(pintype "bidirectional")
			(die_length 22.524)
			(solder_mask_margin 0.02)
		)
		(pad "D14" smd circle
			(at -1.5 -11.5)
			(size 0.5 0.5)
			(property pad_prop_bga)
			(layers "F.Cu" "F.Mask" "F.Paste")
			(net 239 "/FMC+ HSPC/FMC.IO21_P")
			(pinfunction "IO_L21P_T3_DQS_18")
			(pintype "bidirectional")
			(die_length 22.264)
			(solder_mask_margin 0.02)
		)
		(pad "D15" smd circle
			(at -0.5 -11.5)
			(size 0.5 0.5)
			(property pad_prop_bga)
			(layers "F.Cu" "F.Mask" "F.Paste")
			(net 1 "GND")
			(pinfunction "GND")
			(pintype "passive")
			(solder_mask_margin 0.02)
		)
		(pad "D16" smd circle
			(at 0.5 -11.5)
			(size 0.5 0.5)
			(property pad_prop_bga)
			(layers "F.Cu" "F.Mask" "F.Paste")
			(net 505 "/FPGA Bank 16 & 17/GBE_RGMII.RXD1")
			(pinfunction "IO_L15P_T2_DQS_17")
			(pintype "bidirectional")
			(die_length 23.582)
			(solder_mask_margin 0.02)
		)
		(pad "D17" smd circle
			(at 1.5 -11.5)
			(size 0.5 0.5)
			(property pad_prop_bga)
			(layers "F.Cu" "F.Mask" "F.Paste")
			(net 507 "/FPGA Bank 16 & 17/GBE_RGMII.GTR_CLK")
			(pinfunction "IO_L13P_T2_MRCC_17")
			(pintype "bidirectional")
			(die_length 21.562)
			(solder_mask_margin 0.02)
		)
		(pad "D18" smd circle
			(at 2.5 -11.5)
			(size 0.5 0.5)
			(property pad_prop_bga)
			(layers "F.Cu" "F.Mask" "F.Paste")
			(net 523 "/FPGA Bank 16 & 17/GBE_RGMII.MDIO")
			(pinfunction "IO_L13N_T2_MRCC_17")
			(pintype "bidirectional")
			(die_length 21.659)
			(solder_mask_margin 0.02)
		)
		(pad "D19" smd circle
			(at 3.5 -11.5)
			(size 0.5 0.5)
			(property pad_prop_bga)
			(layers "F.Cu" "F.Mask" "F.Paste")
			(net 522 "/FPGA Bank 16 & 17/GBE_RGMII.~{RESET}")
			(pinfunction "IO_L14N_T2_SRCC_17")
			(pintype "bidirectional")
			(die_length 20.704)
			(solder_mask_margin 0.02)
		)
		(pad "D20" smd circle
			(at 4.5 -11.5)
			(size 0.5 0.5)
			(property pad_prop_bga)
			(layers "F.Cu" "F.Mask" "F.Paste")
			(net 24 "+3V3")
			(pinfunction "VCCO_17")
			(pintype "passive")
			(solder_mask_margin 0.02)
		)
		(pad "D21" smd circle
			(at 5.5 -11.5)
			(size 0.5 0.5)
			(property pad_prop_bga)
			(layers "F.Cu" "F.Mask" "F.Paste")
			(net 528 "/FPGA Bank 16 & 17/HDMI.D0_P")
			(pinfunction "IO_L8P_T1_17")
			(pintype "bidirectional")
			(die_length 15.622)
			(solder_mask_margin 0.02)
		)
		(pad "D22" smd circle
			(at 6.5 -11.5)
			(size 0.5 0.5)
			(property pad_prop_bga)
			(layers "F.Cu" "F.Mask" "F.Paste")
			(net 984 "unconnected-(U1C-IO_L10P_T1_17-PadD22)")
			(pinfunction "IO_L10P_T1_17")
			(pintype "bidirectional+no_connect")
			(die_length 15.866)
			(solder_mask_margin 0.02)
		)
		(pad "D23" smd circle
			(at 7.5 -11.5)
			(size 0.5 0.5)
			(property pad_prop_bga)
			(layers "F.Cu" "F.Mask" "F.Paste")
			(net 875 "unconnected-(U1C-IO_L2N_T0_16-PadD23)")
			(pinfunction "IO_L2N_T0_16")
			(pintype "bidirectional+no_connect")
			(die_length 19.449)
			(solder_mask_margin 0.02)
		)
		(pad "D24" smd circle
			(at 8.5 -11.5)
			(size 0.5 0.5)
			(property pad_prop_bga)
			(layers "F.Cu" "F.Mask" "F.Paste")
			(net 877 "unconnected-(U1C-IO_L4N_T0_16-PadD24)")
			(pinfunction "IO_L4N_T0_16")
			(pintype "bidirectional+no_connect")
			(die_length 20.101)
			(solder_mask_margin 0.02)
		)
		(pad "D25" smd circle
			(at 9.5 -11.5)
			(size 0.5 0.5)
			(property pad_prop_bga)
			(layers "F.Cu" "F.Mask" "F.Paste")
			(net 1 "GND")
			(pinfunction "GND")
			(pintype "passive")
			(solder_mask_margin 0.02)
		)
	)
)
